# T6G (Grand Teton) — schematic netlist excerpt (pin names and nets, part order shuffled) for the footprints in the layout excerpt that follows; sources: Cadence DE-HDL packaged netlist, KiCad conversion of 04192023_DAF0TMB3IC0_F0TG_MB_C_brd_V02_OCP.brd

PC310_5  Q_CAP  1UF 25V 10% X6S  pkg C0402  page 213 : A = SW_P12V_AUX_PVDDCR_CPU0_P1_FLT ; B = GND
R6313  Q_RES  0 5% CHIP  pkg 0402LF  page 178 : A = USB_HUB2_TI_OVERCUR2 ; B = USB_HUB2_TI_OVERCUR2_MRP_PROG_FUNC5

(kicad_pcb
	(version 20260206)
	(generator "pcbnew")
	(generator_version "10.0")
	(general
		(thickness 1.6)
		(legacy_teardrops no)
	)
	(paper "A4")
	(title_block
		(title "04192023_DAF0TMB3IC0_F0TG_MB_C_brd_V02_OCP.brd")
		(comment 1 "Grand Teton / footprints 4050-4051 of 8354")
	)
	(layers
		(0 "F.Cu" signal "TOP")
		(4 "In1.Cu" signal "GND")
		(6 "In2.Cu" signal "IN1")
		(8 "In3.Cu" signal "GND1")
		(10 "In4.Cu" signal "IN2")
		(12 "In5.Cu" signal "GND2")
		(14 "In6.Cu" signal "IN3")
		(16 "In7.Cu" signal "GND3")
		(18 "In8.Cu" signal "VCC")
		(20 "In9.Cu" signal "VCC1")
		(22 "In10.Cu" signal "GND4")
		(24 "In11.Cu" signal "IN4")
		(26 "In12.Cu" signal "GND5")
		(28 "In13.Cu" signal "IN5")
		(30 "In14.Cu" signal "GND6")
		(32 "In15.Cu" signal "IN6")
		(34 "In16.Cu" signal "GND7")
		(2 "B.Cu" signal "BOTTOM")
		(9 "F.Adhes" user "F.Adhesive")
		(11 "B.Adhes" user "B.Adhesive")
		(13 "F.Paste" user "Package Geometry/Pastemask Top")
		(15 "B.Paste" user "Package Geometry/Pastemask Bottom")
		(5 "F.SilkS" user "Ref Des/Silkscreen Top")
		(7 "B.SilkS" user "Ref Des/Silkscreen Bottom")
		(1 "F.Mask" user "Board Geometry/Soldermask Top")
		(3 "B.Mask" user "Board Geometry/Soldermask Bottom")
		(17 "Dwgs.User" user "User.Drawings")
		(19 "Cmts.User" user "User.Comments")
		(21 "Eco1.User" user "User.Eco1")
		(23 "Eco2.User" user "User.Eco2")
		(25 "Edge.Cuts" user "Board Geometry/Outline")
		(27 "Margin" user)
		(31 "F.CrtYd" user "Package Geometry/Place Bound Top")
		(29 "B.CrtYd" user "Package Geometry/Place Bound Bottom")
		(35 "F.Fab" user "Ref Des/Assembly Top")
		(33 "B.Fab" user "Ref Des/Assembly Bottom")
	)
	(footprint ""
		(layer "F.Cu")
		(at 70.32117 -177.540666 90)
		(property "Reference" "PC310_5"
			(at 0 0 90)
			(layer "F.SilkS")
			(hide yes)
			(effects
				(font
					(size 1.27 1.27)
				)
			)
		)
		(property "Value" ""
			(at 0 0 90)
			(layer "F.Fab")
			(effects
				(font
					(size 1.27 1.27)
				)
			)
		)
		(duplicate_pad_numbers_are_jumpers no)
		(fp_line
			(start 0.7874 -0.4064)
			(end 0.7874 0.4064)
			(stroke
				(width 0.1524)
				(type default)
			)
			(layer "F.SilkS")
		)
		(fp_line
			(start -0.7874 -0.4064)
			(end 0.7874 -0.4064)
			(stroke
				(width 0.1524)
				(type default)
			)
			(layer "F.SilkS")
		)
		(fp_line
			(start 0.7874 0.4064)
			(end -0.7874 0.4064)
			(stroke
				(width 0.1524)
				(type default)
			)
			(layer "F.SilkS")
		)
		(fp_line
			(start -0.7874 0.4064)
			(end -0.7874 -0.4064)
			(stroke
				(width 0.1524)
				(type default)
			)
			(layer "F.SilkS")
		)
		(fp_line
			(start -0.12065 -0.305054)
			(end -0.12065 -0.2794)
			(stroke
				(width 0.1)
				(type default)
			)
			(layer "F.Fab")
		)
		(fp_line
			(start -0.67945 -0.305054)
			(end -0.12065 -0.305054)
			(stroke
				(width 0.1)
				(type default)
			)
			(layer "F.Fab")
		)
		(fp_line
			(start 0.67945 -0.3048)
			(end 0.67945 0.3048)
			(stroke
				(width 0.1)
				(type default)
			)
			(layer "F.Fab")
		)
		(fp_line
			(start 0.12065 -0.3048)
			(end 0.67945 -0.3048)
			(stroke
				(width 0.1)
				(type default)
			)
			(layer "F.Fab")
		)
		(fp_line
			(start 0.12065 -0.2794)
			(end 0.12065 -0.3048)
			(stroke
				(width 0.1)
				(type default)
			)
			(layer "F.Fab")
		)
		(fp_line
			(start -0.12065 -0.2794)
			(end 0.12065 -0.2794)
			(stroke
				(width 0.1)
				(type default)
			)
			(layer "F.Fab")
		)
		(fp_line
			(start 0.120396 0.2794)
			(end -0.12065 0.2794)
			(stroke
				(width 0.1)
				(type default)
			)
			(layer "F.Fab")
		)
		(fp_line
			(start -0.12065 0.2794)
			(end -0.12065 0.3048)
			(stroke
				(width 0.1)
				(type default)
			)
			(layer "F.Fab")
		)
		(fp_line
			(start 0.67945 0.3048)
			(end 0.120396 0.3048)
			(stroke
				(width 0.1)
				(type default)
			)
			(layer "F.Fab")
		)
		(fp_line
			(start 0.120396 0.3048)
			(end 0.120396 0.2794)
			(stroke
				(width 0.1)
				(type default)
			)
			(layer "F.Fab")
		)
		(fp_line
			(start -0.12065 0.3048)
			(end -0.67945 0.3048)
			(stroke
				(width 0.1)
				(type default)
			)
			(layer "F.Fab")
		)
		(fp_line
			(start -0.67945 0.3048)
			(end -0.67945 -0.305054)
			(stroke
				(width 0.1)
				(type default)
			)
			(layer "F.Fab")
		)
		(pad "1" smd circle
			(at -0.40005 0 90)
			(size 0 0)
			(layers "F.Cu" "F.Mask" "F.Paste")
			(net "SW_P12V_AUX_PVDDCR_CPU0_P1_FLT")
		)
		(pad "2" smd circle
			(at 0.40005 0 90)
			(size 0 0)
			(layers "F.Cu" "F.Mask" "F.Paste")
			(net "GND")
		)
	)
	(footprint ""
		(layer "F.Cu")
		(at 105.485946 -52.86248 -90)
		(property "Reference" "R6313"
			(at 0 0 270)
			(layer "F.SilkS")
			(hide yes)
			(effects
				(font
					(size 1.27 1.27)
				)
			)
		)
		(property "Value" ""
			(at 0 0 270)
			(layer "F.Fab")
			(effects
				(font
					(size 1.27 1.27)
				)
			)
		)
		(duplicate_pad_numbers_are_jumpers no)
		(fp_line
			(start -0.7874 0.4064)
			(end -0.7874 -0.4064)
			(stroke
				(width 0.1524)
				(type default)
			)
			(layer "F.SilkS")
		)
		(fp_line
			(start 0.7874 0.4064)
			(end -0.7874 0.4064)
			(stroke
				(width 0.1524)
				(type default)
			)
			(layer "F.SilkS")
		)
		(fp_line
			(start -0.7874 -0.4064)
			(end 0.7874 -0.4064)
			(stroke
				(width 0.1524)
				(type default)
			)
			(layer "F.SilkS")
		)
		(fp_line
			(start 0.7874 -0.4064)
			(end 0.7874 0.4064)
			(stroke
				(width 0.1524)
				(type default)
			)
			(layer "F.SilkS")
		)
		(fp_line
			(start -0.67945 0.3048)
			(end -0.67945 -0.305054)
			(stroke
				(width 0.1)
				(type default)
			)
			(layer "F.Fab")
		)
		(fp_line
			(start -0.12065 0.3048)
			(end -0.67945 0.3048)
			(stroke
				(width 0.1)
				(type default)
			)
			(layer "F.Fab")
		)
		(fp_line
			(start 0.120396 0.3048)
			(end 0.120396 0.2794)
			(stroke
				(width 0.1)
				(type default)
			)
			(layer "F.Fab")
		)
		(fp_line
			(start 0.67945 0.3048)
			(end 0.120396 0.3048)
			(stroke
				(width 0.1)
				(type default)
			)
			(layer "F.Fab")
		)
		(fp_line
			(start -0.12065 0.2794)
			(end -0.12065 0.3048)
			(stroke
				(width 0.1)
				(type default)
			)
			(layer "F.Fab")
		)
		(fp_line
			(start 0.120396 0.2794)
			(end -0.12065 0.2794)
			(stroke
				(width 0.1)
				(type default)
			)
			(layer "F.Fab")
		)
		(fp_line
			(start -0.12065 -0.2794)
			(end 0.12065 -0.2794)
			(stroke
				(width 0.1)
				(type default)
			)
			(layer "F.Fab")
		)
		(fp_line
			(start 0.12065 -0.2794)
			(end 0.12065 -0.3048)
			(stroke
				(width 0.1)
				(type default)
			)
			(layer "F.Fab")
		)
		(fp_line
			(start 0.12065 -0.3048)
			(end 0.67945 -0.3048)
			(stroke
				(width 0.1)
				(type default)
			)
			(layer "F.Fab")
		)
		(fp_line
			(start 0.67945 -0.3048)
			(end 0.67945 0.3048)
			(stroke
				(width 0.1)
				(type default)
			)
			(layer "F.Fab")
		)
		(fp_line
			(start -0.67945 -0.305054)
			(end -0.12065 -0.305054)
			(stroke
				(width 0.1)
				(type default)
			)
			(layer "F.Fab")
		)
		(fp_line
			(start -0.12065 -0.305054)
			(end -0.12065 -0.2794)
			(stroke
				(width 0.1)
				(type default)
			)
			(layer "F.Fab")
		)
		(pad "1" smd circle
			(at -0.40005 0 270)
			(size 0 0)
			(layers "F.Cu" "F.Mask" "F.Paste")
			(net "USB_HUB2_TI_OVERCUR2")
		)
		(pad "2" smd circle
			(at 0.40005 0 270)
			(size 0 0)
			(layers "F.Cu" "F.Mask" "F.Paste")
			(net "USB_HUB2_TI_OVERCUR2_MRP_PROG_FUNC5")
		)
	)
)
